# T6G (Grand Teton) — schematic netlist excerpt (pin names and nets, part order shuffled) for the footprints in the layout excerpt that follows; sources: Cadence DE-HDL packaged netlist, KiCad conversion of 04192023_DAF0TMB3IC0_F0TG_MB_C_brd_V02_OCP.brd

PR104  Q_RES  0 5% CHIP  pkg 0402LF  page 205 : A = PVDDIO_P0_VOS2 ; B = PVDDIO_P0
R779  Q_RES  0 5% CHIP  pkg 0201LF  page 331 : A = SMB_RT_CPU1_P1_R_SCL ; B = SMB_RT_CPU1_P1_R2_SCL
C237  Q_CAP  2.7PF 50V 0.1PF NPO  pkg C0402  page 55 : A = XTAL_CPU1_X48M_X2_R ; B = GND

(kicad_pcb
	(version 20260206)
	(generator "pcbnew")
	(generator_version "10.0")
	(general
		(thickness 1.6)
		(legacy_teardrops no)
	)
	(paper "A4")
	(title_block
		(title "04192023_DAF0TMB3IC0_F0TG_MB_C_brd_V02_OCP.brd")
		(comment 1 "Grand Teton / footprints 6743-6745 of 8354")
	)
	(layers
		(0 "F.Cu" signal "TOP")
		(4 "In1.Cu" signal "GND")
		(6 "In2.Cu" signal "IN1")
		(8 "In3.Cu" signal "GND1")
		(10 "In4.Cu" signal "IN2")
		(12 "In5.Cu" signal "GND2")
		(14 "In6.Cu" signal "IN3")
		(16 "In7.Cu" signal "GND3")
		(18 "In8.Cu" signal "VCC")
		(20 "In9.Cu" signal "VCC1")
		(22 "In10.Cu" signal "GND4")
		(24 "In11.Cu" signal "IN4")
		(26 "In12.Cu" signal "GND5")
		(28 "In13.Cu" signal "IN5")
		(30 "In14.Cu" signal "GND6")
		(32 "In15.Cu" signal "IN6")
		(34 "In16.Cu" signal "GND7")
		(2 "B.Cu" signal "BOTTOM")
		(9 "F.Adhes" user "F.Adhesive")
		(11 "B.Adhes" user "B.Adhesive")
		(13 "F.Paste" user "Package Geometry/Pastemask Top")
		(15 "B.Paste" user "Package Geometry/Pastemask Bottom")
		(5 "F.SilkS" user "Ref Des/Silkscreen Top")
		(7 "B.SilkS" user "Ref Des/Silkscreen Bottom")
		(1 "F.Mask" user "Board Geometry/Soldermask Top")
		(3 "B.Mask" user "Board Geometry/Soldermask Bottom")
		(17 "Dwgs.User" user "User.Drawings")
		(19 "Cmts.User" user "User.Comments")
		(21 "Eco1.User" user "User.Eco1")
		(23 "Eco2.User" user "User.Eco2")
		(25 "Edge.Cuts" user "Board Geometry/Outline")
		(27 "Margin" user)
		(31 "F.CrtYd" user "Package Geometry/Place Bound Top")
		(29 "B.CrtYd" user "Package Geometry/Place Bound Bottom")
		(35 "F.Fab" user "Ref Des/Assembly Top")
		(33 "B.Fab" user "Ref Des/Assembly Bottom")
	)
	(footprint ""
		(layer "B.Cu")
		(at 149.900386 -314.47105 180)
		(property "Reference" "C237"
			(at 0 0 0)
			(layer "B.SilkS")
			(hide yes)
			(effects
				(font
					(size 1.27 1.27)
				)
				(justify mirror)
			)
		)
		(property "Value" ""
			(at 0 0 0)
			(layer "B.Fab")
			(effects
				(font
					(size 1.27 1.27)
				)
				(justify mirror)
			)
		)
		(duplicate_pad_numbers_are_jumpers no)
		(fp_line
			(start 0.7874 0.4064)
			(end 0.7874 -0.4064)
			(stroke
				(width 0.1524)
				(type default)
			)
			(layer "B.SilkS")
		)
		(fp_line
			(start 0.7874 -0.4064)
			(end -0.7874 -0.4064)
			(stroke
				(width 0.1524)
				(type default)
			)
			(layer "B.SilkS")
		)
		(fp_line
			(start -0.7874 0.4064)
			(end 0.7874 0.4064)
			(stroke
				(width 0.1524)
				(type default)
			)
			(layer "B.SilkS")
		)
		(fp_line
			(start -0.7874 -0.4064)
			(end -0.7874 0.4064)
			(stroke
				(width 0.1524)
				(type default)
			)
			(layer "B.SilkS")
		)
		(fp_line
			(start 0.67945 0.3048)
			(end 0.67945 -0.305054)
			(stroke
				(width 0.1)
				(type default)
			)
			(layer "B.Fab")
		)
		(fp_line
			(start 0.67945 -0.305054)
			(end 0.12065 -0.305054)
			(stroke
				(width 0.1)
				(type default)
			)
			(layer "B.Fab")
		)
		(fp_line
			(start 0.12065 0.3048)
			(end 0.67945 0.3048)
			(stroke
				(width 0.1)
				(type default)
			)
			(layer "B.Fab")
		)
		(fp_line
			(start 0.12065 0.2794)
			(end 0.12065 0.3048)
			(stroke
				(width 0.1)
				(type default)
			)
			(layer "B.Fab")
		)
		(fp_line
			(start 0.12065 -0.2794)
			(end -0.12065 -0.2794)
			(stroke
				(width 0.1)
				(type default)
			)
			(layer "B.Fab")
		)
		(fp_line
			(start 0.12065 -0.305054)
			(end 0.12065 -0.2794)
			(stroke
				(width 0.1)
				(type default)
			)
			(layer "B.Fab")
		)
		(fp_line
			(start -0.120396 0.3048)
			(end -0.120396 0.2794)
			(stroke
				(width 0.1)
				(type default)
			)
			(layer "B.Fab")
		)
		(fp_line
			(start -0.120396 0.2794)
			(end 0.12065 0.2794)
			(stroke
				(width 0.1)
				(type default)
			)
			(layer "B.Fab")
		)
		(fp_line
			(start -0.12065 -0.2794)
			(end -0.12065 -0.3048)
			(stroke
				(width 0.1)
				(type default)
			)
			(layer "B.Fab")
		)
		(fp_line
			(start -0.12065 -0.3048)
			(end -0.67945 -0.3048)
			(stroke
				(width 0.1)
				(type default)
			)
			(layer "B.Fab")
		)
		(fp_line
			(start -0.67945 0.3048)
			(end -0.120396 0.3048)
			(stroke
				(width 0.1)
				(type default)
			)
			(layer "B.Fab")
		)
		(fp_line
			(start -0.67945 -0.3048)
			(end -0.67945 0.3048)
			(stroke
				(width 0.1)
				(type default)
			)
			(layer "B.Fab")
		)
		(pad "1" smd circle
			(at 0.40005 0)
			(size 0 0)
			(layers "B.Cu" "B.Mask" "B.Paste")
			(net "XTAL_CPU1_X48M_X2_R")
		)
		(pad "2" smd circle
			(at -0.40005 0)
			(size 0 0)
			(layers "B.Cu" "B.Mask" "B.Paste")
			(net "GND")
		)
	)
	(footprint ""
		(layer "B.Cu")
		(at 288.346896 -349.381572 -90)
		(property "Reference" "PR104"
			(at 0 0 90)
			(layer "B.SilkS")
			(hide yes)
			(effects
				(font
					(size 1.27 1.27)
				)
				(justify mirror)
			)
		)
		(property "Value" ""
			(at 0 0 90)
			(layer "B.Fab")
			(effects
				(font
					(size 1.27 1.27)
				)
				(justify mirror)
			)
		)
		(duplicate_pad_numbers_are_jumpers no)
		(fp_line
			(start -0.7874 0.4064)
			(end 0.7874 0.4064)
			(stroke
				(width 0.1524)
				(type default)
			)
			(layer "B.SilkS")
		)
		(fp_line
			(start 0.7874 0.4064)
			(end 0.7874 -0.4064)
			(stroke
				(width 0.1524)
				(type default)
			)
			(layer "B.SilkS")
		)
		(fp_line
			(start -0.7874 -0.4064)
			(end -0.7874 0.4064)
			(stroke
				(width 0.1524)
				(type default)
			)
			(layer "B.SilkS")
		)
		(fp_line
			(start 0.7874 -0.4064)
			(end -0.7874 -0.4064)
			(stroke
				(width 0.1524)
				(type default)
			)
			(layer "B.SilkS")
		)
		(fp_line
			(start -0.67945 0.3048)
			(end -0.120396 0.3048)
			(stroke
				(width 0.1)
				(type default)
			)
			(layer "B.Fab")
		)
		(fp_line
			(start -0.120396 0.3048)
			(end -0.120396 0.2794)
			(stroke
				(width 0.1)
				(type default)
			)
			(layer "B.Fab")
		)
		(fp_line
			(start 0.12065 0.3048)
			(end 0.67945 0.3048)
			(stroke
				(width 0.1)
				(type default)
			)
			(layer "B.Fab")
		)
		(fp_line
			(start 0.67945 0.3048)
			(end 0.67945 -0.305054)
			(stroke
				(width 0.1)
				(type default)
			)
			(layer "B.Fab")
		)
		(fp_line
			(start -0.120396 0.2794)
			(end 0.12065 0.2794)
			(stroke
				(width 0.1)
				(type default)
			)
			(layer "B.Fab")
		)
		(fp_line
			(start 0.12065 0.2794)
			(end 0.12065 0.3048)
			(stroke
				(width 0.1)
				(type default)
			)
			(layer "B.Fab")
		)
		(fp_line
			(start -0.12065 -0.2794)
			(end -0.12065 -0.3048)
			(stroke
				(width 0.1)
				(type default)
			)
			(layer "B.Fab")
		)
		(fp_line
			(start 0.12065 -0.2794)
			(end -0.12065 -0.2794)
			(stroke
				(width 0.1)
				(type default)
			)
			(layer "B.Fab")
		)
		(fp_line
			(start -0.67945 -0.3048)
			(end -0.67945 0.3048)
			(stroke
				(width 0.1)
				(type default)
			)
			(layer "B.Fab")
		)
		(fp_line
			(start -0.12065 -0.3048)
			(end -0.67945 -0.3048)
			(stroke
				(width 0.1)
				(type default)
			)
			(layer "B.Fab")
		)
		(fp_line
			(start 0.12065 -0.305054)
			(end 0.12065 -0.2794)
			(stroke
				(width 0.1)
				(type default)
			)
			(layer "B.Fab")
		)
		(fp_line
			(start 0.67945 -0.305054)
			(end 0.12065 -0.305054)
			(stroke
				(width 0.1)
				(type default)
			)
			(layer "B.Fab")
		)
		(pad "1" smd circle
			(at 0.40005 0 90)
			(size 0 0)
			(layers "B.Cu" "B.Mask" "B.Paste")
			(net "PVDDIO_P0_VOS2")
		)
		(pad "2" smd circle
			(at -0.40005 0 90)
			(size 0 0)
			(layers "B.Cu" "B.Mask" "B.Paste")
			(net "PVDDIO_P0")
		)
	)
	(footprint ""
		(layer "B.Cu")
		(at 215.0618 -337.312)
		(property "Reference" "R779"
			(at 0 0 0)
			(layer "B.SilkS")
			(hide yes)
			(effects
				(font
					(size 1.27 1.27)
				)
				(justify mirror)
			)
		)
		(property "Value" ""
			(at 0 0 0)
			(layer "B.Fab")
			(effects
				(font
					(size 1.27 1.27)
				)
				(justify mirror)
			)
		)
		(duplicate_pad_numbers_are_jumpers no)
		(fp_line
			(start -0.32512 -0.175006)
			(end -0.32512 0.175006)
			(stroke
				(width 0.1)
				(type default)
			)
			(layer "B.Fab")
		)
		(fp_line
			(start -0.32512 0.175006)
			(end 0.32512 0.175006)
			(stroke
				(width 0.1)
				(type default)
			)
			(layer "B.Fab")
		)
		(fp_line
			(start 0.32512 -0.175006)
			(end -0.32512 -0.175006)
			(stroke
				(width 0.1)
				(type default)
			)
			(layer "B.Fab")
		)
		(fp_line
			(start 0.32512 0.175006)
			(end 0.32512 -0.175006)
			(stroke
				(width 0.1)
				(type default)
			)
			(layer "B.Fab")
		)
		(pad "1" smd rect
			(at 0.2667 0 180)
			(size 0.3048 0.381)
			(layers "B.Cu" "B.Mask" "B.Paste")
			(net "SMB_RT_CPU1_P1_R_SCL")
		)
		(pad "2" smd rect
			(at -0.2667 0)
			(size 0.3048 0.381)
			(layers "B.Cu" "B.Mask" "B.Paste")
			(net "SMB_RT_CPU1_P1_R2_SCL")
		)
	)
)
